(kicad_pcb
	(version 20260206)
	(generator "pcbnew")
	(generator_version "10.0")
	(general
		(thickness 1.6)
		(legacy_teardrops no)
	)
	(paper "A4")
	(title_block
		(title "01162023_DA0F0TEBIF0_F0T_Expander_BD_F_brd_V02_OCP.brd")
		(comment 1 "Grand Teton / footprints 5412-5418 of 9728")
	)
	(layers
		(0 "F.Cu" signal "TOP")
		(4 "In1.Cu" signal "GND")
		(6 "In2.Cu" signal "VCC")
		(8 "In3.Cu" signal "VCC1")
		(10 "In4.Cu" signal "GND1")
		(12 "In5.Cu" signal "IN1")
		(14 "In6.Cu" signal "GND2")
		(16 "In7.Cu" signal "IN2")
		(18 "In8.Cu" signal "GND3")
		(20 "In9.Cu" signal "IN3")
		(22 "In10.Cu" signal "GND4")
		(24 "In11.Cu" signal "IN4")
		(26 "In12.Cu" signal "GND5")
		(28 "In13.Cu" signal "IN5")
		(30 "In14.Cu" signal "GND6")
		(32 "In15.Cu" signal "IN6")
		(34 "In16.Cu" signal "GND7")
		(2 "B.Cu" signal "BOTTOM")
		(9 "F.Adhes" user "F.Adhesive")
		(11 "B.Adhes" user "B.Adhesive")
		(13 "F.Paste" user "Package Geometry/Pastemask Top")
		(15 "B.Paste" user "Package Geometry/Pastemask Bottom")
		(5 "F.SilkS" user "Ref Des/Silkscreen Top")
		(7 "B.SilkS" user "Ref Des/Silkscreen Bottom")
		(1 "F.Mask" user "Board Geometry/Soldermask Top")
		(3 "B.Mask" user "Board Geometry/Soldermask Bottom")
		(17 "Dwgs.User" user "User.Drawings")
		(19 "Cmts.User" user "User.Comments")
		(21 "Eco1.User" user "User.Eco1")
		(23 "Eco2.User" user "User.Eco2")
		(25 "Edge.Cuts" user "Board Geometry/Outline")
		(27 "Margin" user)
		(31 "F.CrtYd" user "Package Geometry/Place Bound Top")
		(29 "B.CrtYd" user "Package Geometry/Place Bound Bottom")
		(35 "F.Fab" user "Ref Des/Assembly Top")
		(33 "B.Fab" user "Ref Des/Assembly Bottom")
	)
	(footprint ""
		(layer "F.Cu")
		(at 71.247 -217.732356 90)
		(property "Reference" "R6633"
			(at 0 0 90)
			(layer "F.SilkS")
			(hide yes)
			(effects
				(font
					(size 1.27 1.27)
				)
			)
		)
		(property "Value" ""
			(at 0 0 90)
			(layer "F.Fab")
			(effects
				(font
					(size 1.27 1.27)
				)
			)
		)
		(duplicate_pad_numbers_are_jumpers no)
		(fp_line
			(start 0.7874 -0.4064)
			(end 0.7874 0.4064)
			(stroke
				(width 0.1524)
				(type default)
			)
			(layer "F.SilkS")
		)
		(fp_line
			(start -0.7874 -0.4064)
			(end 0.7874 -0.4064)
			(stroke
				(width 0.1524)
				(type default)
			)
			(layer "F.SilkS")
		)
		(fp_line
			(start 0.7874 0.4064)
			(end -0.7874 0.4064)
			(stroke
				(width 0.1524)
				(type default)
			)
			(layer "F.SilkS")
		)
		(fp_line
			(start -0.7874 0.4064)
			(end -0.7874 -0.4064)
			(stroke
				(width 0.1524)
				(type default)
			)
			(layer "F.SilkS")
		)
		(fp_line
			(start -0.12065 -0.305054)
			(end -0.12065 -0.2794)
			(stroke
				(width 0.1)
				(type default)
			)
			(layer "F.Fab")
		)
		(fp_line
			(start -0.67945 -0.305054)
			(end -0.12065 -0.305054)
			(stroke
				(width 0.1)
				(type default)
			)
			(layer "F.Fab")
		)
		(fp_line
			(start 0.67945 -0.3048)
			(end 0.67945 0.3048)
			(stroke
				(width 0.1)
				(type default)
			)
			(layer "F.Fab")
		)
		(fp_line
			(start 0.12065 -0.3048)
			(end 0.67945 -0.3048)
			(stroke
				(width 0.1)
				(type default)
			)
			(layer "F.Fab")
		)
		(fp_line
			(start 0.12065 -0.2794)
			(end 0.12065 -0.3048)
			(stroke
				(width 0.1)
				(type default)
			)
			(layer "F.Fab")
		)
		(fp_line
			(start -0.12065 -0.2794)
			(end 0.12065 -0.2794)
			(stroke
				(width 0.1)
				(type default)
			)
			(layer "F.Fab")
		)
		(fp_line
			(start 0.120396 0.2794)
			(end -0.12065 0.2794)
			(stroke
				(width 0.1)
				(type default)
			)
			(layer "F.Fab")
		)
		(fp_line
			(start -0.12065 0.2794)
			(end -0.12065 0.3048)
			(stroke
				(width 0.1)
				(type default)
			)
			(layer "F.Fab")
		)
		(fp_line
			(start 0.67945 0.3048)
			(end 0.120396 0.3048)
			(stroke
				(width 0.1)
				(type default)
			)
			(layer "F.Fab")
		)
		(fp_line
			(start 0.120396 0.3048)
			(end 0.120396 0.2794)
			(stroke
				(width 0.1)
				(type default)
			)
			(layer "F.Fab")
		)
		(fp_line
			(start -0.12065 0.3048)
			(end -0.67945 0.3048)
			(stroke
				(width 0.1)
				(type default)
			)
			(layer "F.Fab")
		)
		(fp_line
			(start -0.67945 0.3048)
			(end -0.67945 -0.305054)
			(stroke
				(width 0.1)
				(type default)
			)
			(layer "F.Fab")
		)
		(pad "1" smd circle
			(at -0.40005 0 90)
			(size 0 0)
			(layers "F.Cu" "F.Mask" "F.Paste")
			(net "UART_PEX3_CLI_R_RX")
		)
		(pad "2" smd circle
			(at 0.40005 0 90)
			(size 0 0)
			(layers "F.Cu" "F.Mask" "F.Paste")
			(net "UART_PEX3_CLI_R1_RX")
		)
	)
	(footprint ""
		(layer "F.Cu")
		(at 236.58195 -254.18542 -90)
		(property "Reference" "C4354"
			(at 0 0 270)
			(layer "F.SilkS")
			(hide yes)
			(effects
				(font
					(size 1.27 1.27)
				)
			)
		)
		(property "Value" ""
			(at 0 0 270)
			(layer "F.Fab")
			(effects
				(font
					(size 1.27 1.27)
				)
			)
		)
		(duplicate_pad_numbers_are_jumpers no)
		(fp_line
			(start -1.2954 0.5842)
			(end -1.2954 -0.5842)
			(stroke
				(width 0.1524)
				(type default)
			)
			(layer "F.SilkS")
		)
		(fp_line
			(start 1.2954 0.5842)
			(end -1.2954 0.5842)
			(stroke
				(width 0.1524)
				(type default)
			)
			(layer "F.SilkS")
		)
		(fp_line
			(start -1.2954 -0.5842)
			(end 1.2954 -0.5842)
			(stroke
				(width 0.1524)
				(type default)
			)
			(layer "F.SilkS")
		)
		(fp_line
			(start 1.2954 -0.5842)
			(end 1.2954 0.5842)
			(stroke
				(width 0.1524)
				(type default)
			)
			(layer "F.SilkS")
		)
		(fp_line
			(start -0.8636 0.4572)
			(end -0.8636 0.4064)
			(stroke
				(width 0.1)
				(type default)
			)
			(layer "F.Fab")
		)
		(fp_line
			(start 0.8636 0.4572)
			(end -0.8636 0.4572)
			(stroke
				(width 0.1)
				(type default)
			)
			(layer "F.Fab")
		)
		(fp_line
			(start -1.1938 0.4064)
			(end -1.1938 -0.4064)
			(stroke
				(width 0.1)
				(type default)
			)
			(layer "F.Fab")
		)
		(fp_line
			(start -0.8636 0.4064)
			(end -1.1938 0.4064)
			(stroke
				(width 0.1)
				(type default)
			)
			(layer "F.Fab")
		)
		(fp_line
			(start 0.8636 0.4064)
			(end 0.8636 0.4572)
			(stroke
				(width 0.1)
				(type default)
			)
			(layer "F.Fab")
		)
		(fp_line
			(start 1.1938 0.4064)
			(end 0.8636 0.4064)
			(stroke
				(width 0.1)
				(type default)
			)
			(layer "F.Fab")
		)
		(fp_line
			(start -1.1938 -0.4064)
			(end -0.8636 -0.4064)
			(stroke
				(width 0.1)
				(type default)
			)
			(layer "F.Fab")
		)
		(fp_line
			(start -0.8636 -0.4064)
			(end -0.8636 -0.4572)
			(stroke
				(width 0.1)
				(type default)
			)
			(layer "F.Fab")
		)
		(fp_line
			(start 0.8636 -0.4064)
			(end 1.1938 -0.4064)
			(stroke
				(width 0.1)
				(type default)
			)
			(layer "F.Fab")
		)
		(fp_line
			(start 1.1938 -0.4064)
			(end 1.1938 0.4064)
			(stroke
				(width 0.1)
				(type default)
			)
			(layer "F.Fab")
		)
		(fp_line
			(start -0.8636 -0.4572)
			(end 0.8636 -0.4572)
			(stroke
				(width 0.1)
				(type default)
			)
			(layer "F.Fab")
		)
		(fp_line
			(start 0.8636 -0.4572)
			(end 0.8636 -0.4064)
			(stroke
				(width 0.1)
				(type default)
			)
			(layer "F.Fab")
		)
		(pad "1" smd rect
			(at -0.7366 0 180)
			(size 0.7112 0.8128)
			(layers "F.Cu" "F.Mask" "F.Paste")
			(net "P1V25_SERDES_VDDPLL_PEX2_C8")
		)
		(pad "2" smd rect
			(at 0.7366 0 180)
			(size 0.7112 0.8128)
			(layers "F.Cu" "F.Mask" "F.Paste")
			(net "GND")
		)
	)
	(footprint ""
		(layer "F.Cu")
		(at 123.67514 -97.177606)
		(property "Reference" "R1575"
			(at 0 0 0)
			(layer "F.SilkS")
			(hide yes)
			(effects
				(font
					(size 1.27 1.27)
				)
			)
		)
		(property "Value" ""
			(at 0 0 0)
			(layer "F.Fab")
			(effects
				(font
					(size 1.27 1.27)
				)
			)
		)
		(duplicate_pad_numbers_are_jumpers no)
		(fp_line
			(start -0.7874 -0.4064)
			(end 0.7874 -0.4064)
			(stroke
				(width 0.1524)
				(type default)
			)
			(layer "F.SilkS")
		)
		(fp_line
			(start -0.7874 0.4064)
			(end -0.7874 -0.4064)
			(stroke
				(width 0.1524)
				(type default)
			)
			(layer "F.SilkS")
		)
		(fp_line
			(start 0.7874 -0.4064)
			(end 0.7874 0.4064)
			(stroke
				(width 0.1524)
				(type default)
			)
			(layer "F.SilkS")
		)
		(fp_line
			(start 0.7874 0.4064)
			(end -0.7874 0.4064)
			(stroke
				(width 0.1524)
				(type default)
			)
			(layer "F.SilkS")
		)
		(fp_line
			(start -0.67945 -0.305054)
			(end -0.12065 -0.305054)
			(stroke
				(width 0.1)
				(type default)
			)
			(layer "F.Fab")
		)
		(fp_line
			(start -0.67945 0.3048)
			(end -0.67945 -0.305054)
			(stroke
				(width 0.1)
				(type default)
			)
			(layer "F.Fab")
		)
		(fp_line
			(start -0.12065 -0.305054)
			(end -0.12065 -0.2794)
			(stroke
				(width 0.1)
				(type default)
			)
			(layer "F.Fab")
		)
		(fp_line
			(start -0.12065 -0.2794)
			(end 0.12065 -0.2794)
			(stroke
				(width 0.1)
				(type default)
			)
			(layer "F.Fab")
		)
		(fp_line
			(start -0.12065 0.2794)
			(end -0.12065 0.3048)
			(stroke
				(width 0.1)
				(type default)
			)
			(layer "F.Fab")
		)
		(fp_line
			(start -0.12065 0.3048)
			(end -0.67945 0.3048)
			(stroke
				(width 0.1)
				(type default)
			)
			(layer "F.Fab")
		)
		(fp_line
			(start 0.120396 0.2794)
			(end -0.12065 0.2794)
			(stroke
				(width 0.1)
				(type default)
			)
			(layer "F.Fab")
		)
		(fp_line
			(start 0.120396 0.3048)
			(end 0.120396 0.2794)
			(stroke
				(width 0.1)
				(type default)
			)
			(layer "F.Fab")
		)
		(fp_line
			(start 0.12065 -0.3048)
			(end 0.67945 -0.3048)
			(stroke
				(width 0.1)
				(type default)
			)
			(layer "F.Fab")
		)
		(fp_line
			(start 0.12065 -0.2794)
			(end 0.12065 -0.3048)
			(stroke
				(width 0.1)
				(type default)
			)
			(layer "F.Fab")
		)
		(fp_line
			(start 0.67945 -0.3048)
			(end 0.67945 0.3048)
			(stroke
				(width 0.1)
				(type default)
			)
			(layer "F.Fab")
		)
		(fp_line
			(start 0.67945 0.3048)
			(end 0.120396 0.3048)
			(stroke
				(width 0.1)
				(type default)
			)
			(layer "F.Fab")
		)
		(pad "1" smd circle
			(at -0.40005 0)
			(size 0 0)
			(layers "F.Cu" "F.Mask" "F.Paste")
			(net "SMB_BIC_I2C9_MUX0_SSD0_R_SDA")
		)
		(pad "2" smd circle
			(at 0.40005 0)
			(size 0 0)
			(layers "F.Cu" "F.Mask" "F.Paste")
			(net "SMB_BIC_I2C9_MUX0_SSD0_SDA")
		)
	)
	(footprint ""
		(layer "F.Cu")
		(at 137.985754 -27.092148 -90)
		(property "Reference" "R5739"
			(at 0 0 270)
			(layer "F.SilkS")
			(hide yes)
			(effects
				(font
					(size 1.27 1.27)
				)
			)
		)
		(property "Value" ""
			(at 0 0 270)
			(layer "F.Fab")
			(effects
				(font
					(size 1.27 1.27)
				)
			)
		)
		(duplicate_pad_numbers_are_jumpers no)
		(fp_line
			(start -0.7874 0.4064)
			(end -0.7874 -0.4064)
			(stroke
				(width 0.1524)
				(type default)
			)
			(layer "F.SilkS")
		)
		(fp_line
			(start 0.7874 0.4064)
			(end -0.7874 0.4064)
			(stroke
				(width 0.1524)
				(type default)
			)
			(layer "F.SilkS")
		)
		(fp_line
			(start -0.7874 -0.4064)
			(end 0.7874 -0.4064)
			(stroke
				(width 0.1524)
				(type default)
			)
			(layer "F.SilkS")
		)
		(fp_line
			(start 0.7874 -0.4064)
			(end 0.7874 0.4064)
			(stroke
				(width 0.1524)
				(type default)
			)
			(layer "F.SilkS")
		)
		(fp_line
			(start -0.67945 0.3048)
			(end -0.67945 -0.305054)
			(stroke
				(width 0.1)
				(type default)
			)
			(layer "F.Fab")
		)
		(fp_line
			(start -0.12065 0.3048)
			(end -0.67945 0.3048)
			(stroke
				(width 0.1)
				(type default)
			)
			(layer "F.Fab")
		)
		(fp_line
			(start 0.120396 0.3048)
			(end 0.120396 0.2794)
			(stroke
				(width 0.1)
				(type default)
			)
			(layer "F.Fab")
		)
		(fp_line
			(start 0.67945 0.3048)
			(end 0.120396 0.3048)
			(stroke
				(width 0.1)
				(type default)
			)
			(layer "F.Fab")
		)
		(fp_line
			(start -0.12065 0.2794)
			(end -0.12065 0.3048)
			(stroke
				(width 0.1)
				(type default)
			)
			(layer "F.Fab")
		)
		(fp_line
			(start 0.120396 0.2794)
			(end -0.12065 0.2794)
			(stroke
				(width 0.1)
				(type default)
			)
			(layer "F.Fab")
		)
		(fp_line
			(start -0.12065 -0.2794)
			(end 0.12065 -0.2794)
			(stroke
				(width 0.1)
				(type default)
			)
			(layer "F.Fab")
		)
		(fp_line
			(start 0.12065 -0.2794)
			(end 0.12065 -0.3048)
			(stroke
				(width 0.1)
				(type default)
			)
			(layer "F.Fab")
		)
		(fp_line
			(start 0.12065 -0.3048)
			(end 0.67945 -0.3048)
			(stroke
				(width 0.1)
				(type default)
			)
			(layer "F.Fab")
		)
		(fp_line
			(start 0.67945 -0.3048)
			(end 0.67945 0.3048)
			(stroke
				(width 0.1)
				(type default)
			)
			(layer "F.Fab")
		)
		(fp_line
			(start -0.67945 -0.305054)
			(end -0.12065 -0.305054)
			(stroke
				(width 0.1)
				(type default)
			)
			(layer "F.Fab")
		)
		(fp_line
			(start -0.12065 -0.305054)
			(end -0.12065 -0.2794)
			(stroke
				(width 0.1)
				(type default)
			)
			(layer "F.Fab")
		)
		(pad "1" smd circle
			(at -0.40005 0 270)
			(size 0 0)
			(layers "F.Cu" "F.Mask" "F.Paste")
			(net "P3V3_SSD4")
		)
		(pad "2" smd circle
			(at 0.40005 0 270)
			(size 0 0)
			(layers "F.Cu" "F.Mask" "F.Paste")
			(net "SSD4_LED_ISO_N")
		)
	)
	(footprint ""
		(layer "F.Cu")
		(at 242.232434 -250.759722 -90)
		(property "Reference" "R6220"
			(at 0 0 270)
			(layer "F.SilkS")
			(hide yes)
			(effects
				(font
					(size 1.27 1.27)
				)
			)
		)
		(property "Value" ""
			(at 0 0 270)
			(layer "F.Fab")
			(effects
				(font
					(size 1.27 1.27)
				)
			)
		)
		(duplicate_pad_numbers_are_jumpers no)
		(fp_line
			(start -0.7874 0.4064)
			(end -0.7874 -0.4064)
			(stroke
				(width 0.1524)
				(type default)
			)
			(layer "F.SilkS")
		)
		(fp_line
			(start 0.7874 0.4064)
			(end -0.7874 0.4064)
			(stroke
				(width 0.1524)
				(type default)
			)
			(layer "F.SilkS")
		)
		(fp_line
			(start -0.7874 -0.4064)
			(end 0.7874 -0.4064)
			(stroke
				(width 0.1524)
				(type default)
			)
			(layer "F.SilkS")
		)
		(fp_line
			(start 0.7874 -0.4064)
			(end 0.7874 0.4064)
			(stroke
				(width 0.1524)
				(type default)
			)
			(layer "F.SilkS")
		)
		(fp_line
			(start -0.67945 0.3048)
			(end -0.67945 -0.305054)
			(stroke
				(width 0.1)
				(type default)
			)
			(layer "F.Fab")
		)
		(fp_line
			(start -0.12065 0.3048)
			(end -0.67945 0.3048)
			(stroke
				(width 0.1)
				(type default)
			)
			(layer "F.Fab")
		)
		(fp_line
			(start 0.120396 0.3048)
			(end 0.120396 0.2794)
			(stroke
				(width 0.1)
				(type default)
			)
			(layer "F.Fab")
		)
		(fp_line
			(start 0.67945 0.3048)
			(end 0.120396 0.3048)
			(stroke
				(width 0.1)
				(type default)
			)
			(layer "F.Fab")
		)
		(fp_line
			(start -0.12065 0.2794)
			(end -0.12065 0.3048)
			(stroke
				(width 0.1)
				(type default)
			)
			(layer "F.Fab")
		)
		(fp_line
			(start 0.120396 0.2794)
			(end -0.12065 0.2794)
			(stroke
				(width 0.1)
				(type default)
			)
			(layer "F.Fab")
		)
		(fp_line
			(start -0.12065 -0.2794)
			(end 0.12065 -0.2794)
			(stroke
				(width 0.1)
				(type default)
			)
			(layer "F.Fab")
		)
		(fp_line
			(start 0.12065 -0.2794)
			(end 0.12065 -0.3048)
			(stroke
				(width 0.1)
				(type default)
			)
			(layer "F.Fab")
		)
		(fp_line
			(start 0.12065 -0.3048)
			(end 0.67945 -0.3048)
			(stroke
				(width 0.1)
				(type default)
			)
			(layer "F.Fab")
		)
		(fp_line
			(start 0.67945 -0.3048)
			(end 0.67945 0.3048)
			(stroke
				(width 0.1)
				(type default)
			)
			(layer "F.Fab")
		)
		(fp_line
			(start -0.67945 -0.305054)
			(end -0.12065 -0.305054)
			(stroke
				(width 0.1)
				(type default)
			)
			(layer "F.Fab")
		)
		(fp_line
			(start -0.12065 -0.305054)
			(end -0.12065 -0.2794)
			(stroke
				(width 0.1)
				(type default)
			)
			(layer "F.Fab")
		)
		(pad "1" smd circle
			(at -0.40005 0 270)
			(size 0 0)
			(layers "F.Cu" "F.Mask" "F.Paste")
			(net "P3V3_AUX")
		)
		(pad "2" smd circle
			(at 0.40005 0 270)
			(size 0 0)
			(layers "F.Cu" "F.Mask" "F.Paste")
			(net "RST_BIC_RECOVER_N")
		)
	)
	(footprint ""
		(layer "F.Cu")
		(at 268.838426 -105.609898)
		(property "Reference" "C480"
			(at 0 0 0)
			(layer "F.SilkS")
			(hide yes)
			(effects
				(font
					(size 1.27 1.27)
				)
			)
		)
		(property "Value" ""
			(at 0 0 0)
			(layer "F.Fab")
			(effects
				(font
					(size 1.27 1.27)
				)
			)
		)
		(duplicate_pad_numbers_are_jumpers no)
		(fp_line
			(start -0.299974 -0.150114)
			(end 0.299974 -0.150114)
			(stroke
				(width 0.1)
				(type default)
			)
			(layer "F.Fab")
		)
		(fp_line
			(start -0.299974 0.150114)
			(end -0.299974 -0.150114)
			(stroke
				(width 0.1)
				(type default)
			)
			(layer "F.Fab")
		)
		(fp_line
			(start 0.299974 -0.150114)
			(end 0.299974 0.150114)
			(stroke
				(width 0.1)
				(type default)
			)
			(layer "F.Fab")
		)
		(fp_line
			(start 0.299974 0.150114)
			(end -0.299974 0.150114)
			(stroke
				(width 0.1)
				(type default)
			)
			(layer "F.Fab")
		)
		(pad "1" smd rect
			(at -0.2667 0)
			(size 0.3048 0.381)
			(layers "F.Cu" "F.Mask" "F.Paste")
			(net "P5E_PEX2_STN1_TX_DP<19>")
		)
		(pad "2" smd rect
			(at 0.2667 0)
			(size 0.3048 0.381)
			(layers "F.Cu" "F.Mask" "F.Paste")
			(net "P5E_PEX2_STN1_TX_C_DP<19>")
		)
	)
	(footprint ""
		(layer "F.Cu")
		(at 431.594006 -35.264852)
		(property "Reference" "R5708"
			(at 0 0 0)
			(layer "F.SilkS")
			(hide yes)
			(effects
				(font
					(size 1.27 1.27)
				)
			)
		)
		(property "Value" ""
			(at 0 0 0)
			(layer "F.Fab")
			(effects
				(font
					(size 1.27 1.27)
				)
			)
		)
		(duplicate_pad_numbers_are_jumpers no)
		(fp_line
			(start -0.7874 -0.4064)
			(end 0.7874 -0.4064)
			(stroke
				(width 0.1524)
				(type default)
			)
			(layer "F.SilkS")
		)
		(fp_line
			(start -0.7874 0.4064)
			(end -0.7874 -0.4064)
			(stroke
				(width 0.1524)
				(type default)
			)
			(layer "F.SilkS")
		)
		(fp_line
			(start 0.7874 -0.4064)
			(end 0.7874 0.4064)
			(stroke
				(width 0.1524)
				(type default)
			)
			(layer "F.SilkS")
		)
		(fp_line
			(start 0.7874 0.4064)
			(end -0.7874 0.4064)
			(stroke
				(width 0.1524)
				(type default)
			)
			(layer "F.SilkS")
		)
		(fp_line
			(start -0.67945 -0.305054)
			(end -0.12065 -0.305054)
			(stroke
				(width 0.1)
				(type default)
			)
			(layer "F.Fab")
		)
		(fp_line
			(start -0.67945 0.3048)
			(end -0.67945 -0.305054)
			(stroke
				(width 0.1)
				(type default)
			)
			(layer "F.Fab")
		)
		(fp_line
			(start -0.12065 -0.305054)
			(end -0.12065 -0.2794)
			(stroke
				(width 0.1)
				(type default)
			)
			(layer "F.Fab")
		)
		(fp_line
			(start -0.12065 -0.2794)
			(end 0.12065 -0.2794)
			(stroke
				(width 0.1)
				(type default)
			)
			(layer "F.Fab")
		)
		(fp_line
			(start -0.12065 0.2794)
			(end -0.12065 0.3048)
			(stroke
				(width 0.1)
				(type default)
			)
			(layer "F.Fab")
		)
		(fp_line
			(start -0.12065 0.3048)
			(end -0.67945 0.3048)
			(stroke
				(width 0.1)
				(type default)
			)
			(layer "F.Fab")
		)
		(fp_line
			(start 0.120396 0.2794)
			(end -0.12065 0.2794)
			(stroke
				(width 0.1)
				(type default)
			)
			(layer "F.Fab")
		)
		(fp_line
			(start 0.120396 0.3048)
			(end 0.120396 0.2794)
			(stroke
				(width 0.1)
				(type default)
			)
			(layer "F.Fab")
		)
		(fp_line
			(start 0.12065 -0.3048)
			(end 0.67945 -0.3048)
			(stroke
				(width 0.1)
				(type default)
			)
			(layer "F.Fab")
		)
		(fp_line
			(start 0.12065 -0.2794)
			(end 0.12065 -0.3048)
			(stroke
				(width 0.1)
				(type default)
			)
			(layer "F.Fab")
		)
		(fp_line
			(start 0.67945 -0.3048)
			(end 0.67945 0.3048)
			(stroke
				(width 0.1)
				(type default)
			)
			(layer "F.Fab")
		)
		(fp_line
			(start 0.67945 0.3048)
			(end 0.120396 0.3048)
			(stroke
				(width 0.1)
				(type default)
			)
			(layer "F.Fab")
		)
		(pad "1" smd circle
			(at -0.40005 0)
			(size 0 0)
			(layers "F.Cu" "F.Mask" "F.Paste")
			(net "RST_SMB_SSD15_ISO_N")
		)
		(pad "2" smd circle
			(at 0.40005 0)
			(size 0 0)
			(layers "F.Cu" "F.Mask" "F.Paste")
			(net "GND")
		)
	)
)
